# S9S_MB_2U (Grand Teton) — schematic parts with pin connectivity, parts 1487–1593 of 6093; source: Cadence DE-HDL packaged netlist (pstxprt.dat, pstxnet.dat, pstchip.dat)

D79  Q_LED  IC  pkg SMLF  page 253 : A = LED_PWRGD_PVCCIN_CPU0 ; C = LED_PWRGD_PVCCIN_CPU0_D
D80  Q_LED  IC  pkg SMLF  page 254 : A = LED_PWRGD_PVCCD_HV_CPU1 ; C = LED_PWRGD_PVCCD_HV_CPU1_D
D81  Q_LED  IC  pkg SMLF  page 254 : A = LED_PWRGD_PVPP_HBM_CPU1 ; C = LED_PWRGD_PVPP_HBM_CPU1_D
D82  Q_LED  IC  pkg SMLF  page 254 : A = LED_PWRGD_PVCCFA_EHV_CPU1 ; C = LED_PWRGD_PVCCFA_EHV_CPU1_D
D83  Q_LED  IC  pkg SMLF  page 254 : A = LED_PWRGD_PVCCFA_EHV_FIVRA_CPU1 ; C = LED_PWRGD_PVCCFA_EHV_FIVRA_CP_2
D84  Q_LED  IC  pkg SMLF  page 254 : A = LED_PWRGD_PVCCINFAON_CPU1 ; C = LED_PWRGD_PVCCINFAON_CPU1_D
D85  Q_LED  IC  pkg SMLF  page 254 : A = LED_PWRGD_PVNN_MAIN_CPU1 ; C = LED_PWRGD_PVNN_MAIN_CPU1_D
D86  Q_LED  IC  pkg SMLF  page 254 : A = LED_PWRGD_PVCCIN_CPU1 ; C = LED_PWRGD_PVCCIN_CPU1_D
D87  Q_LED  IC  pkg SMLF  page 255 : A = LED_PWRGD_PCH_PWROK_R ; C = LED_PWRGD_PCH_PWROK_R_D
D88  Q_LED  IC  pkg SMLF  page 255 : A = LED_PWRGD_SYS_PWROK_R ; C = LED_PWRGD_SYS_PWROK_R_D
D89  Q_LED  IC  pkg SMLF  page 255 : A = LED_PWRGD_CPUPWRGD_GTL ; C = LED_PWRGD_CPUPWRGD_GTL_D
D90  Q_LED  IC  pkg SMLF  page 255 : A = LED_RST_PLTRST_N ; C = LED_RST_PLTRST_N_D
D91  Q_LED  IC  pkg SMLF  page 252 : A = LED_PWRGD_P1V8_PCH_AUX ; C = LED_PWRGD_P1V8_PCH_AUX_D
D92  Q_LED  IC  pkg SMLF  page 252 : A = LED_PWRGD_P1V05_PCH_AUX ; C = LED_PWRGD_P1V05_PCH_AUX_D
D93  Q_LED  IC  pkg SMLF  page 252 : A = LED_RST_RSMRST_PLD_R_N ; C = LED_RST_RSMRST_PLD_R_N_D
D94  Q_LED  IC  pkg SMLF  page 252 : A = LED_FM_PCH_SLP_S4_N ; C = LED_FM_PCH_SLP_S4_N_D
D95  Q_LED  IC  pkg SMLF  page 252 : A = LED_FM_PCH_SLP_S3_N ; C = LED_FM_PCH_SLP_S3_N_D
D96  Q_LED  IC  pkg SMLF  page 252 : A = LED_PWRGD_PS_PWROK_PLD ; C = LED_PWRGD_PS_PWROK_PLD_D
D97  Q_LED  IC  pkg SMLF  page 252 : A = LED_P5V_AUX ; C = GND
D98  Q_LED  IC  pkg SMLF  page 252 : A = LED_P5V ; C = GND
D99  Q_LED  IC  pkg SMLF  page 252 : A = LED_P3V3 ; C = GND
D141  SCHOTTKY_12  1N5819HW IC  pkg SOD123  page 221 : 1 = P3V3_AUX ; 2 = P3V3_AUX_BMC_D
D142  Q_LED  IC  pkg SMLF  page 255 : A = LED_P12V_AUX_R1 ; C = GND
D143  Q_LED  IC  pkg SMLF  page 255 : A = LED_P12V_PSU_R1 ; C = GND
D144  Q_LED  IC  pkg SMLF  page 255 : A = LED_P12V_SCM_FAULT ; C = LED_P12V_SCM_FAULT_D2
D145  Q_DIODE  SDMK0340L-7-F IC  pkg SMLF  page 259 : 1 = MB0_P12V_STBY_PWRGD ; 2 = P3V3_AUX_EN

DB1  TDR_3P  EMPTY  pkg TH2  page 309
  1  GND  UNSPEC  = T1_GND
  2  IO1  UNSPEC  = TDR_SE_40_OHM_TOP
  3  IO2  UNSPEC  = TDR_SE_40_OHM_TOP

DB2  TDR_3P  EMPTY  pkg TH2  page 309
  1  GND  UNSPEC  = T1_GND
  2  IO1  UNSPEC  = TDR_SE_40_OHM_IN1
  3  IO2  UNSPEC  = TDR_SE_40_OHM_IN1

DB3  TDR_3P  EMPTY  pkg TH2  page 309
  1  GND  UNSPEC  = T1_GND
  2  IO1  UNSPEC  = TDR_SE_40_OHM_IN2
  3  IO2  UNSPEC  = TDR_SE_40_OHM_IN2

DB4  TDR_3P  EMPTY  pkg TH2  page 309
  1  GND  UNSPEC  = T1_GND
  2  IO1  UNSPEC  = TDR_SE_40_OHM_IN3
  3  IO2  UNSPEC  = TDR_SE_40_OHM_IN3

DB5  TDR_3P  EMPTY  pkg TH2  page 309
  1  GND  UNSPEC  = T1_GND
  2  IO1  UNSPEC  = TDR_SE_40_OHM_IN4
  3  IO2  UNSPEC  = TDR_SE_40_OHM_IN4

DB6  TDR_3P  EMPTY  pkg TH2  page 309
  1  GND  UNSPEC  = T1_GND
  2  IO1  UNSPEC  = TDR_SE_40_OHM_BOT
  3  IO2  UNSPEC  = TDR_SE_40_OHM_BOT

DB7  TDR_3P  EMPTY  pkg TH2  page 309
  1  GND  UNSPEC  = T1_GND
  2  IO1  UNSPEC  = TDR_SE_50_OHM_TOP
  3  IO2  UNSPEC  = TDR_SE_50_OHM_TOP

DB8  TDR_3P  EMPTY  pkg TH2  page 309
  1  GND  UNSPEC  = T1_GND
  2  IO1  UNSPEC  = TDR_SE_50_OHM_IN1
  3  IO2  UNSPEC  = TDR_SE_50_OHM_IN1

DB9  TDR_3P  EMPTY  pkg TH2  page 309
  1  GND  UNSPEC  = T1_GND
  2  IO1  UNSPEC  = TDR_SE_50_OHM_IN2
  3  IO2  UNSPEC  = TDR_SE_50_OHM_IN2

DB10  TDR_3P  EMPTY  pkg TH2  page 309
  1  GND  UNSPEC  = T1_GND
  2  IO1  UNSPEC  = TDR_SE_50_OHM_IN3
  3  IO2  UNSPEC  = TDR_SE_50_OHM_IN3

DB11  TDR_3P  EMPTY  pkg TH2  page 309
  1  GND  UNSPEC  = T1_GND
  2  IO1  UNSPEC  = TDR_SE_50_OHM_IN4
  3  IO2  UNSPEC  = TDR_SE_50_OHM_IN4

DB12  TDR_3P  EMPTY  pkg TH2  page 309
  1  GND  UNSPEC  = T1_GND
  2  IO1  UNSPEC  = TDR_SE_50_OHM_BOT
  3  IO2  UNSPEC  = TDR_SE_50_OHM_BOT

DB13  TDR_3P  EMPTY  pkg TH2  page 309
  1  GND  UNSPEC  = T1_GND
  2  IO1  UNSPEC  = TDR_SE_40_OHM_IN5
  3  IO2  UNSPEC  = TDR_SE_40_OHM_IN5

DB14  TDR_3P  EMPTY  pkg TH2  page 309
  1  GND  UNSPEC  = T1_GND
  2  IO1  UNSPEC  = TDR_SE_40_OHM_IN6
  3  IO2  UNSPEC  = TDR_SE_40_OHM_IN6

DB15  TDR_3P  EMPTY  pkg TH2  page 309
  1  GND  UNSPEC  = T1_GND
  2  IO1  UNSPEC  = TDR_SE_50_OHM_IN5
  3  IO2  UNSPEC  = TDR_SE_50_OHM_IN5

DB16  TDR_3P  EMPTY  pkg TH2  page 309
  1  GND  UNSPEC  = T1_GND
  2  IO1  UNSPEC  = TDR_SE_50_OHM_IN6
  3  IO2  UNSPEC  = TDR_SE_50_OHM_IN6

DM9  DUMMY_SYMBOL  MECHANIC_SYMBOL MECH  pkg TP30_FOR_BOM  page 312 : 1 = NC
DM13  DUMMY_SYMBOL  BATTERY_SYMBOL MECH  pkg TP30_FOR_BOM  page 312 : 1 = NC
FS1  Q_FUSE  20A/125V IC  pkg SMLF  page 304 : 1 = P12V_PSU ; 2 = P12V_PSU_FUSE
H15  HOLE  EMPTY  pkg TH  page 311 : 1 = NC
H16  HOLE  EMPTY  pkg TH  page 311 : 1 = NC
H17  HOLE  EMPTY  pkg TH  page 311 : 1 = NC
H18  HOLE  EMPTY  pkg TH  page 311 : 1 = NC
H19  HOLE  EMPTY  pkg TH  page 311 : 1 = NC
H20  HOLE  EMPTY  pkg TH  page 311 : 1 = NC
H21  HOLE  EMPTY  pkg TH  page 311 : 1 = NC
H22  HOLE  EMPTY  pkg TH  page 311 : 1 = NC
H23  HOLE  EMPTY  pkg TH  page 311 : 1 = NC
H24  HOLE  EMPTY  pkg TH  page 311 : 1 = NC
H25  HOLE  EMPTY  pkg TH  page 311 : 1 = NC
H26  HOLE  EMPTY  pkg TH  page 311 : 1 = NC
H27  HOLE  EMPTY  pkg TH  page 311 : 1 = NC
H28  HOLE  EMPTY  pkg TH  page 311 : 1 = NC
H29  HOLE  EMPTY  pkg TH  page 311 : 1 = NC
H30  HOLE  EMPTY  pkg TH  page 311 : 1 = NC
H31  HOLE  EMPTY  pkg TH  page 311 : 1 = GND
H32  HOLE  EMPTY  pkg TH  page 311 : 1 = GND
H36  HOLE  EMPTY  pkg TH  page 311 : 1 = NC
H38  HOLE  EMPTY  pkg TH  page 311 : 1 = NC
H44  HOLE  EMPTY  pkg TH  page 311 : 1 = GND
H45  HOLE  EMPTY  pkg TH  page 311 : 1 = GND
H47  HOLE  EMPTY  pkg TH  page 311 : 1 = GND
H49  HOLE  EMPTY  pkg TH  page 311 : 1 = GND
H74  HOLE  EMPTY  pkg TH  page 311 : 1 = NC
H75  HOLE  EMPTY  pkg TH  page 311 : 1 = NC
H76  HOLE  EMPTY  pkg TH  page 311 : 1 = GND
H77  HOLE  EMPTY  pkg TH  page 311 : 1 = GND
H86  HOLE  EMPTY  pkg TH  page 311 : 1 = GND
H87  HOLE  EMPTY  pkg TH  page 311 : 1 = GND
H88  HOLE  EMPTY  pkg TH  page 311 : 1 = GND
H89  HOLE  EMPTY  pkg TH  page 311 : 1 = GND
H90  HOLE  EMPTY  pkg TH  page 311 : 1 = NC
H91  HOLE  EMPTY  pkg TH  page 311 : 1 = GND
H92  HOLE  EMPTY  pkg TH  page 311 : 1 = GND
H93  HOLE  EMPTY  pkg TH  page 311 : 1 = GND
H94  HOLE  EMPTY  pkg TH  page 311 : 1 = GND
H95  HOLE  EMPTY  pkg TH  page 311 : 1 = GND
H96  HOLE  EMPTY  pkg TH  page 311 : 1 = GND
H97  HOLE  EMPTY  pkg TH  page 311 : 1 = GND
H98  HOLE  EMPTY  pkg TH  page 311 : 1 = GND
H99  HOLE  EMPTY  pkg TH  page 311 : 1 = GND
H100  HOLE  EMPTY  pkg TH  page 311 : 1 = GND
H101  HOLE  EMPTY  pkg TH  page 311 : 1 = GND
H102  HOLE  EMPTY  pkg TH  page 311 : 1 = GND
H103  HOLE  EMPTY  pkg TH  page 311 : 1 = GND
H104  HOLE  EMPTY  pkg TH  page 311 : 1 = GND
H105  HOLE  EMPTY  pkg TH  page 311 : 1 = GND
H106  HOLE  EMPTY  pkg TH  page 311 : 1 = GND

H111  GND_HOLE  EMPTY  pkg TH  page 311
  2  GND2  POWER  = GND
  3  GND3  POWER  = GND
  4  GND4  POWER  = GND
  5  GND5  POWER  = GND
  6  GND6  POWER  = GND
  7  GND7  POWER  = GND
  8  GND8  POWER  = GND
  9  GND9  POWER  = GND

H112  GND_HOLE  EMPTY  pkg TH  page 311
  2  GND2  POWER  = GND
  3  GND3  POWER  = GND
  4  GND4  POWER  = GND
  5  GND5  POWER  = GND
  6  GND6  POWER  = GND
  7  GND7  POWER  = GND
  8  GND8  POWER  = GND
  9  GND9  POWER  = GND

H113  GND_HOLE  EMPTY  pkg TH  page 311
  2  GND2  POWER  = GND
  3  GND3  POWER  = GND
  4  GND4  POWER  = GND
  5  GND5  POWER  = GND
  6  GND6  POWER  = GND
  7  GND7  POWER  = GND
  8  GND8  POWER  = GND
  9  GND9  POWER  = GND

H114  GND_HOLE  EMPTY  pkg TH  page 311
  2  GND2  POWER  = GND
  3  GND3  POWER  = GND
  4  GND4  POWER  = GND
  5  GND5  POWER  = GND
  6  GND6  POWER  = GND
  7  GND7  POWER  = GND
  8  GND8  POWER  = GND
  9  GND9  POWER  = GND

H115  GND_HOLE  EMPTY  pkg TH  page 311
  2  GND2  POWER  = GND
  3  GND3  POWER  = GND
  4  GND4  POWER  = GND
  5  GND5  POWER  = GND
  6  GND6  POWER  = GND
  7  GND7  POWER  = GND
  8  GND8  POWER  = GND
  9  GND9  POWER  = GND

H120  HOLE  EMPTY  pkg TH  page 311 : 1 = NC
H122  HOLE  EMPTY  pkg TH  page 311 : 1 = NC
H124  HOLE  EMPTY  pkg TH  page 311 : 1 = NC
H125  HOLE  EMPTY  pkg TH  page 311 : 1 = NC
H126  HOLE  EMPTY  pkg TH  page 311 : 1 = NC
H127  HOLE  EMPTY  pkg TH  page 311 : 1 = NC
H128  HOLE  EMPTY  pkg TH  page 311 : 1 = GND
H129  HOLE  EMPTY  pkg TH  page 311 : 1 = GND
